G04 ================== begin FILE IDENTIFICATION RECORD ==================*
G04 Layout Name:  12433-2a.brd*
G04 Film Name:    BMASK*
G04 File Format:  Gerber RS274X*
G04 File Origin:  Cadence Allegro 16.5-S056*
G04 Origin Date:  Fri Dec 11 16:47:32 2015*
G04 *
G04 Layer:  VIA CLASS/SOLDERMASK_BOTTOM*
G04 Layer:  PIN/SOLDERMASK_BOTTOM*
G04 Layer:  PACKAGE GEOMETRY/SOLDERMASK_BOTTOM*
G04 Layer:  DRAWING FORMAT/LAYER_PCB_STORY*
G04 Layer:  DRAWING FORMAT/LAYER_SOLDER_B*
G04 Layer:  BOARD GEOMETRY/SOLDERMASK_BOTTOM*
G04 *
G04 Offset:    (0.00 0.00)*
G04 Mirror:    No*
G04 Mode:      Positive*
G04 Rotation:  0*
G04 FullContactRelief:  No*
G04 UndefLineWidth:     6.00*
G04 ================== end FILE IDENTIFICATION RECORD ====================*
%FSLAX35Y35*MOIN*%
%IR0*IPPOS*OFA0.00000B0.00000*MIA0B0*SFA1.00000B1.00000*%
%ADD15C,.05*%
%ADD16C,.028*%
%ADD13C,.056*%
%ADD20C,.057*%
%ADD19C,.099*%
%ADD10C,.14*%
%ADD17C,.115*%
%ADD12C,.142*%
%ADD18C,.126*%
%ADD14C,.315*%
%ADD22R,.12X.12*%
%ADD11R,.16X.16*%
%ADD21C,.375*%
%ADD23C,.02*%
%ADD24C,.006*%
G75*
%LPD*%
G75*
G54D10*
X-222440Y19685D03*
Y1948818D03*
X643700Y19685D03*
Y1948818D03*
G54D11*
X-181139Y20007D03*
X-180444Y1947256D03*
X601704Y21248D03*
X602399Y1948497D03*
G54D20*
X80709Y161889D03*
Y171889D03*
Y181889D03*
Y191889D03*
Y204409D03*
Y214409D03*
Y224409D03*
Y234409D03*
Y244409D03*
Y256929D03*
Y266929D03*
Y276929D03*
Y286929D03*
X110709Y161889D03*
Y171889D03*
X100709Y161889D03*
Y171889D03*
X90709Y161889D03*
Y171889D03*
X110709Y181889D03*
Y191889D03*
X100709Y181889D03*
Y191889D03*
X90709Y181889D03*
Y191889D03*
X110709Y204409D03*
Y214409D03*
Y224409D03*
Y234409D03*
Y244409D03*
X100709Y204409D03*
Y214409D03*
Y224409D03*
Y234409D03*
Y244409D03*
X90709Y204409D03*
Y214409D03*
Y224409D03*
Y234409D03*
Y244409D03*
X110709Y256929D03*
Y266929D03*
X100709Y256929D03*
Y266929D03*
X90709Y256929D03*
Y266929D03*
X110709Y276929D03*
Y286929D03*
X100709Y276929D03*
Y286929D03*
X90709Y276929D03*
Y286929D03*
X179606Y161889D03*
Y171889D03*
X169606Y161889D03*
Y171889D03*
X159606Y161889D03*
Y171889D03*
X149606Y161889D03*
Y171889D03*
X179606Y181889D03*
Y191889D03*
X169606Y181889D03*
Y191889D03*
X159606Y181889D03*
Y191889D03*
X149606Y181889D03*
Y191889D03*
X179606Y204409D03*
Y214409D03*
Y224409D03*
Y234409D03*
Y244409D03*
X169606Y204409D03*
Y214409D03*
Y224409D03*
Y234409D03*
Y244409D03*
X159606Y204409D03*
Y214409D03*
Y224409D03*
Y234409D03*
Y244409D03*
X149606Y204409D03*
Y214409D03*
Y224409D03*
Y234409D03*
Y244409D03*
X179606Y256929D03*
Y266929D03*
X169606Y256929D03*
Y266929D03*
X159606Y256929D03*
Y266929D03*
X149606Y256929D03*
Y266929D03*
X179606Y276929D03*
Y286929D03*
X169606Y276929D03*
Y286929D03*
X159606Y276929D03*
Y286929D03*
X149606Y276929D03*
Y286929D03*
G54D21*
X96457Y1747835D03*
Y1823031D03*
X178937Y1328740D03*
X161417Y1747835D03*
Y1823031D03*
G54D12*
X29921Y24803D03*
Y111417D03*
Y458031D03*
Y544646D03*
Y717874D03*
Y804488D03*
X30000Y1164000D03*
X29921Y1250630D03*
Y1423858D03*
Y1510472D03*
Y1857086D03*
Y1943701D03*
G54D22*
X150000Y64500D03*
X152500Y1906000D03*
G54D13*
X15906Y48110D03*
Y58110D03*
Y68110D03*
Y78110D03*
Y88110D03*
Y481339D03*
Y491339D03*
Y501339D03*
Y511339D03*
Y521339D03*
Y741181D03*
Y751181D03*
Y761181D03*
Y771181D03*
Y781181D03*
Y1187323D03*
Y1197323D03*
Y1207323D03*
Y1217323D03*
Y1227323D03*
Y1447165D03*
Y1457165D03*
Y1467165D03*
Y1477165D03*
Y1487165D03*
Y1880394D03*
Y1890394D03*
Y1900394D03*
Y1910394D03*
Y1920394D03*
X138937Y1778819D03*
X128937D03*
X118937D03*
X165000Y1370500D03*
Y1390500D03*
Y1380500D03*
G54D23*
G01X-448201Y-66763D02*
X-480201D01*
G01X-448201Y-82763D02*
Y-162763D01*
G01Y-118263D02*
X752899D01*
G01X-448201Y-162763D02*
X752899D01*
G01X-452201Y-66763D02*
G02I-12000J0D01*
G01X-457351D02*
G02I-6850J0D01*
G01X-464201Y-82763D02*
Y-50763D01*
G01X-448201Y-82763D02*
X752899D01*
G01X-34601D02*
Y-162763D01*
G01X102899Y-82763D02*
Y-162763D01*
G01X217899Y-82763D02*
Y-162763D01*
G01X385399Y-82763D02*
Y-162763D01*
G01X555399Y-82763D02*
Y-162763D01*
G01X752899Y-82763D02*
Y-162763D01*
G01X780899Y-66763D02*
G02I-12000J0D01*
G01X775749D02*
G02I-6850J0D01*
G01X768899Y-82763D02*
Y-50763D01*
G01X784899Y-66763D02*
X752899D01*
G54D14*
X27559Y157480D03*
Y629921D03*
X17716Y1338583D03*
X27559Y1811023D03*
X179134Y78740D03*
X179133Y570866D03*
X179134Y1161417D03*
Y1889764D03*
G54D24*
G01X-430254Y-152763D02*
Y-135263D01*
G01X-421958D02*
X-430254Y-146055D01*
G01X-420648Y-152763D02*
X-426543Y-141097D01*
G01X-412973Y-152763D02*
Y-135263D01*
X-402929Y-152763D01*
Y-135263D01*
G01X-390451Y-152763D02*
X-392198Y-152471D01*
X-393726Y-151305D01*
X-395036Y-149555D01*
X-395910Y-147513D01*
X-396346Y-145180D01*
Y-142846D01*
X-395910Y-140513D01*
X-395036Y-138471D01*
X-393726Y-136722D01*
X-392198Y-135555D01*
X-390451Y-135263D01*
X-388705Y-135555D01*
X-387176Y-136722D01*
X-385866Y-138471D01*
X-384992Y-140513D01*
X-384556Y-142846D01*
Y-145180D01*
X-384992Y-147513D01*
X-385866Y-149555D01*
X-387176Y-151305D01*
X-388705Y-152471D01*
X-390451Y-152763D01*
G01X-377536D02*
X-368366Y-135263D01*
G01X-377536D02*
X-368366Y-152763D01*
G01X-362001Y-158596D02*
X-348901D01*
G01X-342099Y-152763D02*
Y-135263D01*
X-333803D01*
G01X-336859Y-143721D02*
X-342099D01*
G01X-325910Y-152763D02*
X-320451Y-135263D01*
X-314992Y-152763D01*
G01X-316958Y-146638D02*
X-323945D01*
G01X-307973Y-152763D02*
Y-135263D01*
X-297929Y-152763D01*
Y-135263D01*
G01X-263148Y-136722D02*
X-264458Y-135846D01*
X-265986Y-135263D01*
X-267733D01*
X-269698Y-136138D01*
X-271226Y-137596D01*
X-272318Y-139347D01*
X-273191Y-142263D01*
X-273410Y-144888D01*
X-272973Y-147513D01*
X-272318Y-149263D01*
X-271008Y-151013D01*
X-269479Y-152180D01*
X-267951Y-152763D01*
X-266423D01*
X-264894Y-152180D01*
X-263584Y-151305D01*
X-262492Y-150139D01*
G01X-250451Y-152763D02*
X-252198Y-152471D01*
X-253726Y-151305D01*
X-255036Y-149555D01*
X-255910Y-147513D01*
X-256346Y-145180D01*
Y-142846D01*
X-255910Y-140513D01*
X-255036Y-138471D01*
X-253726Y-136722D01*
X-252198Y-135555D01*
X-250451Y-135263D01*
X-248705Y-135555D01*
X-247176Y-136722D01*
X-245866Y-138471D01*
X-244992Y-140513D01*
X-244556Y-142846D01*
Y-145180D01*
X-244992Y-147513D01*
X-245866Y-149555D01*
X-247176Y-151305D01*
X-248705Y-152471D01*
X-250451Y-152763D01*
G01X-237973D02*
Y-135263D01*
X-227929Y-152763D01*
Y-135263D01*
G01X-215451D02*
Y-152763D01*
G01X-220473Y-135263D02*
X-210429D01*
G01X-202318Y-152763D02*
Y-135263D01*
X-196859D01*
X-195113Y-136138D01*
X-194021Y-137305D01*
X-193584Y-139638D01*
X-194021Y-141972D01*
X-195331Y-143430D01*
X-196859Y-144305D01*
X-202318D01*
G01X-196859D02*
X-193584Y-152763D01*
G01X-180451D02*
X-182198Y-152471D01*
X-183726Y-151305D01*
X-185036Y-149555D01*
X-185910Y-147513D01*
X-186346Y-145180D01*
Y-142846D01*
X-185910Y-140513D01*
X-185036Y-138471D01*
X-183726Y-136722D01*
X-182198Y-135555D01*
X-180451Y-135263D01*
X-178705Y-135555D01*
X-177176Y-136722D01*
X-175866Y-138471D01*
X-174992Y-140513D01*
X-174556Y-142846D01*
Y-145180D01*
X-174992Y-147513D01*
X-175866Y-149555D01*
X-177176Y-151305D01*
X-178705Y-152471D01*
X-180451Y-152763D01*
G01X-167318Y-135263D02*
Y-152763D01*
X-158584D01*
G01X-126205Y-143430D02*
X-125331Y-142555D01*
X-124676Y-141097D01*
X-124239Y-139054D01*
X-124676Y-137305D01*
X-125549Y-136138D01*
X-127078Y-135263D01*
X-132973D01*
Y-152763D01*
X-125768D01*
X-124239Y-151597D01*
X-123366Y-149846D01*
X-122929Y-147805D01*
X-123366Y-145763D01*
X-124676Y-144013D01*
X-126205Y-143430D01*
X-132973D01*
G01X-110451Y-152763D02*
X-112198Y-152471D01*
X-113726Y-151305D01*
X-115036Y-149555D01*
X-115910Y-147513D01*
X-116346Y-145180D01*
Y-142846D01*
X-115910Y-140513D01*
X-115036Y-138471D01*
X-113726Y-136722D01*
X-112198Y-135555D01*
X-110451Y-135263D01*
X-108705Y-135555D01*
X-107176Y-136722D01*
X-105866Y-138471D01*
X-104992Y-140513D01*
X-104556Y-142846D01*
Y-145180D01*
X-104992Y-147513D01*
X-105866Y-149555D01*
X-107176Y-151305D01*
X-108705Y-152471D01*
X-110451Y-152763D01*
G01X-98410D02*
X-92951Y-135263D01*
X-87492Y-152763D01*
G01X-89458Y-146638D02*
X-96445D01*
G01X-79818Y-152763D02*
Y-135263D01*
X-74359D01*
X-72613Y-136138D01*
X-71521Y-137305D01*
X-71084Y-139638D01*
X-71521Y-141972D01*
X-72831Y-143430D01*
X-74359Y-144305D01*
X-79818D01*
G01X-74359D02*
X-71084Y-152763D01*
G01X-62754D02*
Y-135263D01*
X-58388D01*
X-56641Y-136138D01*
X-55331Y-137305D01*
X-54239Y-139054D01*
X-53366Y-141097D01*
X-53148Y-144013D01*
X-53366Y-146930D01*
X-54239Y-148972D01*
X-55331Y-150722D01*
X-56641Y-151888D01*
X-58388Y-152763D01*
X-62754D01*
G01X-282378Y-107763D02*
Y-90263D01*
X-276701Y-104846D01*
X-271024Y-90263D01*
Y-107763D01*
G01X-259201D02*
X-260511Y-107471D01*
X-261821Y-106305D01*
X-262695Y-104263D01*
X-263131Y-101930D01*
X-262695Y-99596D01*
X-261821Y-97555D01*
X-260511Y-96388D01*
X-259201Y-96097D01*
X-257891Y-96388D01*
X-256581Y-97555D01*
X-255708Y-99596D01*
X-255489Y-101930D01*
X-255708Y-104263D01*
X-256581Y-106305D01*
X-257891Y-107471D01*
X-259201Y-107763D01*
G01X-237771Y-90263D02*
Y-107763D01*
G01Y-105139D02*
X-238644Y-106597D01*
X-239955Y-107471D01*
X-241483Y-107763D01*
X-243229Y-107180D01*
X-244539Y-105722D01*
X-245413Y-103972D01*
X-245631Y-101930D01*
X-245413Y-99888D01*
X-244539Y-98138D01*
X-243229Y-96680D01*
X-241483Y-96097D01*
X-239955Y-96388D01*
X-238863Y-96972D01*
X-237771Y-98138D01*
G01X-227476Y-99888D02*
X-220489D01*
X-221144Y-97846D01*
X-222236Y-96680D01*
X-223764Y-96097D01*
X-225293Y-96388D01*
X-226603Y-97263D01*
X-227476Y-99305D01*
X-227913Y-101055D01*
Y-102805D01*
X-227476Y-104555D01*
X-226384Y-106305D01*
X-225074Y-107471D01*
X-223546Y-107763D01*
X-222018Y-107180D01*
X-220489Y-105430D01*
G01X-206701Y-107763D02*
Y-90263D01*
G01X-14018Y-107763D02*
Y-90263D01*
X-8778D01*
X-7031Y-91138D01*
X-5721Y-93180D01*
X-5284Y-95513D01*
X-5721Y-97846D01*
X-6813Y-99596D01*
X-8778Y-100472D01*
X-14018D01*
G01X12652Y-91722D02*
X11342Y-90846D01*
X9814Y-90263D01*
X8067D01*
X6102Y-91138D01*
X4574Y-92596D01*
X3482Y-94347D01*
X2609Y-97263D01*
X2390Y-99888D01*
X2827Y-102513D01*
X3482Y-104263D01*
X4792Y-106013D01*
X6321Y-107180D01*
X7849Y-107763D01*
X9377D01*
X10906Y-107180D01*
X12216Y-106305D01*
X13308Y-105139D01*
G01X27095Y-98430D02*
X27969Y-97555D01*
X28624Y-96097D01*
X29061Y-94054D01*
X28624Y-92305D01*
X27751Y-91138D01*
X26222Y-90263D01*
X20327D01*
Y-107763D01*
X27532D01*
X29061Y-106597D01*
X29934Y-104846D01*
X30371Y-102805D01*
X29934Y-100763D01*
X28624Y-99013D01*
X27095Y-98430D01*
X20327D01*
G01X36299Y-113596D02*
X49399D01*
G01X55327Y-107763D02*
Y-90263D01*
X65371Y-107763D01*
Y-90263D01*
G01X77849Y-107763D02*
X76102Y-107471D01*
X74574Y-106305D01*
X73264Y-104555D01*
X72390Y-102513D01*
X71954Y-100180D01*
Y-97846D01*
X72390Y-95513D01*
X73264Y-93471D01*
X74574Y-91722D01*
X76102Y-90555D01*
X77849Y-90263D01*
X79595Y-90555D01*
X81124Y-91722D01*
X82434Y-93471D01*
X83308Y-95513D01*
X83744Y-97846D01*
Y-100180D01*
X83308Y-102513D01*
X82434Y-104555D01*
X81124Y-106305D01*
X79595Y-107471D01*
X77849Y-107763D01*
G01X-901Y-152763D02*
Y-135263D01*
X-3521Y-138763D01*
G01Y-152763D02*
X1719D01*
G01X12451Y-138180D02*
X13761Y-136430D01*
X15289Y-135555D01*
X17036Y-135263D01*
X19219Y-135846D01*
X20747Y-137305D01*
X21184Y-139054D01*
X20966Y-140805D01*
X20092Y-142263D01*
X15726Y-145180D01*
X13761Y-147221D01*
X12451Y-150139D01*
X12014Y-152763D01*
X21184D01*
G01X36719D02*
Y-135263D01*
X28640Y-147805D01*
X39558D01*
G01X46796Y-149263D02*
X48105Y-151305D01*
X49852Y-152471D01*
X51817Y-152763D01*
X53564Y-152471D01*
X55311Y-151013D01*
X56402Y-149263D01*
X56621Y-147513D01*
X56184Y-145472D01*
X54656Y-144013D01*
X53127Y-143430D01*
X51162D01*
G01X53127D02*
X54437Y-142555D01*
X55529Y-141097D01*
X55966Y-139347D01*
X55529Y-137596D01*
X54437Y-136138D01*
X52472Y-135263D01*
X50507Y-135555D01*
X48542Y-136722D01*
G01X64296Y-149263D02*
X65605Y-151305D01*
X67352Y-152471D01*
X69317Y-152763D01*
X71064Y-152471D01*
X72811Y-151013D01*
X73902Y-149263D01*
X74121Y-147513D01*
X73684Y-145472D01*
X72156Y-144013D01*
X70627Y-143430D01*
X68662D01*
G01X70627D02*
X71937Y-142555D01*
X73029Y-141097D01*
X73466Y-139347D01*
X73029Y-137596D01*
X71937Y-136138D01*
X69972Y-135263D01*
X68007Y-135555D01*
X66042Y-136722D01*
G01X128690Y-90263D02*
X134149Y-107763D01*
X139608Y-90263D01*
G01X156016Y-107763D02*
X147282D01*
Y-90263D01*
X156016D01*
G01X152522Y-98721D02*
X147282D01*
G01X164782Y-107763D02*
Y-90263D01*
X170241D01*
X171987Y-91138D01*
X173079Y-92305D01*
X173516Y-94638D01*
X173079Y-96972D01*
X171769Y-98430D01*
X170241Y-99305D01*
X164782D01*
G01X170241D02*
X173516Y-107763D01*
G01X186649Y-108346D02*
X186212Y-108055D01*
Y-107471D01*
X186649Y-107180D01*
X187086Y-107471D01*
Y-108055D01*
X186649Y-108346D01*
G01X147501Y-138180D02*
X148811Y-136430D01*
X150339Y-135555D01*
X152086Y-135263D01*
X154269Y-135846D01*
X155797Y-137305D01*
X156234Y-139054D01*
X156016Y-140805D01*
X155142Y-142263D01*
X150776Y-145180D01*
X148811Y-147221D01*
X147501Y-150139D01*
X147064Y-152763D01*
X156234D01*
G01X163690D02*
X169149Y-135263D01*
X174608Y-152763D01*
G01X172642Y-146638D02*
X165655D01*
G01X253482Y-90263D02*
Y-107763D01*
X262216D01*
G01X279279D02*
Y-96097D01*
G01Y-98138D02*
X278406Y-96972D01*
X277095Y-96388D01*
X275567Y-96097D01*
X274039Y-96680D01*
X272729Y-97846D01*
X271855Y-99596D01*
X271419Y-101930D01*
X271855Y-104263D01*
X272729Y-106013D01*
X274039Y-107180D01*
X275567Y-107763D01*
X277095Y-107471D01*
X278406Y-106597D01*
X279279Y-105430D01*
G01X288264Y-113013D02*
X289574Y-113596D01*
X291321Y-113013D01*
X292412Y-111847D01*
X293286Y-110388D01*
X294595Y-105722D01*
X297434Y-96097D01*
G01X290447D02*
X294595Y-105722D01*
G01X307074Y-99888D02*
X314061D01*
X313406Y-97846D01*
X312314Y-96680D01*
X310786Y-96097D01*
X309257Y-96388D01*
X307947Y-97263D01*
X307074Y-99305D01*
X306637Y-101055D01*
Y-102805D01*
X307074Y-104555D01*
X308166Y-106305D01*
X309476Y-107471D01*
X311004Y-107763D01*
X312532Y-107180D01*
X314061Y-105430D01*
G01X324792Y-107763D02*
Y-96097D01*
G01Y-98430D02*
X325884Y-97263D01*
X326976Y-96388D01*
X328504Y-96097D01*
X329595Y-96388D01*
X330906Y-97263D01*
G01X342074Y-105722D02*
X343166Y-106888D01*
X344694Y-107763D01*
X346004D01*
X347314Y-107180D01*
X348187Y-106305D01*
X348624Y-105139D01*
X348406Y-103388D01*
X347532Y-102513D01*
X343602Y-100763D01*
X342729Y-98721D01*
X343166Y-97263D01*
X344039Y-96388D01*
X345349Y-96097D01*
X346659Y-96388D01*
X347969Y-97263D01*
G01X334853Y-143430D02*
X333979Y-142555D01*
X333324Y-141097D01*
X332887Y-139054D01*
X333324Y-137305D01*
X334197Y-136138D01*
X335726Y-135263D01*
X341621D01*
Y-152763D01*
X334416D01*
X332887Y-151597D01*
X332014Y-149846D01*
X331577Y-147805D01*
X332014Y-145763D01*
X333324Y-144013D01*
X334853Y-143430D01*
X341621D01*
G01X324776Y-152763D02*
Y-135263D01*
X319099Y-149846D01*
X313422Y-135263D01*
Y-152763D01*
G01X307058D02*
X301599Y-135263D01*
X296140Y-152763D01*
G01X298106Y-146638D02*
X305093D01*
G01X288684Y-150430D02*
X286937Y-151888D01*
X284972Y-152763D01*
X283226D01*
X281479Y-151888D01*
X280169Y-150430D01*
X279514Y-148388D01*
X279951Y-146347D01*
X281042Y-144596D01*
X283007Y-143430D01*
X285627Y-142846D01*
X287156Y-141680D01*
X287811Y-139638D01*
X287374Y-137596D01*
X286282Y-136138D01*
X284754Y-135263D01*
X283226D01*
X281697Y-135846D01*
X280387Y-137305D01*
G01X271402Y-152763D02*
Y-135263D01*
G01X263106D02*
X271402Y-146055D01*
G01X261796Y-152763D02*
X267691Y-141097D01*
G01X404346Y-107763D02*
Y-90263D01*
X408712D01*
X410459Y-91138D01*
X411769Y-92305D01*
X412861Y-94054D01*
X413734Y-96097D01*
X413952Y-99013D01*
X413734Y-101930D01*
X412861Y-103972D01*
X411769Y-105722D01*
X410459Y-106888D01*
X408712Y-107763D01*
X404346D01*
G01X423374Y-99888D02*
X430361D01*
X429706Y-97846D01*
X428614Y-96680D01*
X427086Y-96097D01*
X425557Y-96388D01*
X424247Y-97263D01*
X423374Y-99305D01*
X422937Y-101055D01*
Y-102805D01*
X423374Y-104555D01*
X424466Y-106305D01*
X425776Y-107471D01*
X427304Y-107763D01*
X428832Y-107180D01*
X430361Y-105430D01*
G01X440874Y-105722D02*
X441966Y-106888D01*
X443494Y-107763D01*
X444804D01*
X446114Y-107180D01*
X446987Y-106305D01*
X447424Y-105139D01*
X447206Y-103388D01*
X446332Y-102513D01*
X442402Y-100763D01*
X441529Y-98721D01*
X441966Y-97263D01*
X442839Y-96388D01*
X444149Y-96097D01*
X445459Y-96388D01*
X446769Y-97263D01*
G01X461649Y-96097D02*
Y-107763D01*
G01Y-91430D02*
X461212Y-91138D01*
Y-90555D01*
X461649Y-90263D01*
X462086Y-90555D01*
Y-91138D01*
X461649Y-91430D01*
G01X476092Y-112138D02*
X477621Y-113305D01*
X479367Y-113596D01*
X480895Y-113305D01*
X482206Y-111847D01*
X483079Y-109805D01*
Y-96097D01*
G01Y-98430D02*
X482206Y-97263D01*
X480895Y-96388D01*
X479367Y-96097D01*
X477621Y-96680D01*
X476529Y-97846D01*
X475655Y-99888D01*
X475219Y-101930D01*
X475437Y-103680D01*
X476311Y-105722D01*
X477621Y-107180D01*
X479367Y-107763D01*
X480677Y-107471D01*
X482206Y-106305D01*
X483079Y-105139D01*
G01X492937Y-107763D02*
Y-96097D01*
G01Y-99013D02*
X493811Y-97555D01*
X495121Y-96388D01*
X496867Y-96097D01*
X498395Y-96388D01*
X499706Y-97555D01*
X500361Y-99596D01*
Y-107763D01*
G01X510874Y-99888D02*
X517861D01*
X517206Y-97846D01*
X516114Y-96680D01*
X514586Y-96097D01*
X513057Y-96388D01*
X511747Y-97263D01*
X510874Y-99305D01*
X510437Y-101055D01*
Y-102805D01*
X510874Y-104555D01*
X511966Y-106305D01*
X513276Y-107471D01*
X514804Y-107763D01*
X516332Y-107180D01*
X517861Y-105430D01*
G01X528592Y-107763D02*
Y-96097D01*
G01Y-98430D02*
X529684Y-97263D01*
X530776Y-96388D01*
X532304Y-96097D01*
X533395Y-96388D01*
X534706Y-97263D01*
G01X429722Y-152763D02*
Y-135263D01*
X435399Y-149846D01*
X441076Y-135263D01*
Y-152763D01*
G01X452899D02*
X451152Y-152471D01*
X449624Y-151305D01*
X448314Y-149555D01*
X447440Y-147513D01*
X447004Y-145180D01*
Y-142846D01*
X447440Y-140513D01*
X448314Y-138471D01*
X449624Y-136722D01*
X451152Y-135555D01*
X452899Y-135263D01*
X454645Y-135555D01*
X456174Y-136722D01*
X457484Y-138471D01*
X458358Y-140513D01*
X458794Y-142846D01*
Y-145180D01*
X458358Y-147513D01*
X457484Y-149555D01*
X456174Y-151305D01*
X454645Y-152471D01*
X452899Y-152763D01*
G01X465814Y-150430D02*
X467561Y-151888D01*
X469526Y-152763D01*
X471272D01*
X473019Y-151888D01*
X474329Y-150430D01*
X474984Y-148388D01*
X474547Y-146347D01*
X473456Y-144596D01*
X471491Y-143430D01*
X468871Y-142846D01*
X467342Y-141680D01*
X466687Y-139638D01*
X467124Y-137596D01*
X468216Y-136138D01*
X469744Y-135263D01*
X471272D01*
X472801Y-135846D01*
X474111Y-137305D01*
G01X483314Y-150430D02*
X485061Y-151888D01*
X487026Y-152763D01*
X488772D01*
X490519Y-151888D01*
X491829Y-150430D01*
X492484Y-148388D01*
X492047Y-146347D01*
X490956Y-144596D01*
X488991Y-143430D01*
X486371Y-142846D01*
X484842Y-141680D01*
X484187Y-139638D01*
X484624Y-137596D01*
X485716Y-136138D01*
X487244Y-135263D01*
X488772D01*
X490301Y-135846D01*
X491611Y-137305D01*
G01X509766Y-152763D02*
X501032D01*
Y-135263D01*
X509766D01*
G01X506272Y-143721D02*
X501032D01*
G01X575349Y-152763D02*
Y-135263D01*
X572729Y-138763D01*
G01Y-152763D02*
X577969D01*
G01X588701Y-138180D02*
X590011Y-136430D01*
X591539Y-135555D01*
X593286Y-135263D01*
X595469Y-135846D01*
X596997Y-137305D01*
X597434Y-139054D01*
X597216Y-140805D01*
X596342Y-142263D01*
X591976Y-145180D01*
X590011Y-147221D01*
X588701Y-150139D01*
X588264Y-152763D01*
X597434D01*
G01X606419Y-153346D02*
X614279Y-135263D01*
G01X627849Y-152763D02*
Y-135263D01*
X625229Y-138763D01*
G01Y-152763D02*
X630469D01*
G01X645349D02*
Y-135263D01*
X642729Y-138763D01*
G01Y-152763D02*
X647969D01*
G01X658919Y-153346D02*
X666779Y-135263D01*
G01X676201Y-138180D02*
X677511Y-136430D01*
X679039Y-135555D01*
X680786Y-135263D01*
X682969Y-135846D01*
X684497Y-137305D01*
X684934Y-139054D01*
X684716Y-140805D01*
X683842Y-142263D01*
X679476Y-145180D01*
X677511Y-147221D01*
X676201Y-150139D01*
X675764Y-152763D01*
X684934D01*
G01X697849Y-135263D02*
X696102Y-135846D01*
X694792Y-137305D01*
X693919Y-139054D01*
X693264Y-141388D01*
X693046Y-144013D01*
X693264Y-146638D01*
X693919Y-148972D01*
X694792Y-150722D01*
X696102Y-152180D01*
X697849Y-152763D01*
X699595Y-152180D01*
X700906Y-150722D01*
X701779Y-148972D01*
X702434Y-146638D01*
X702652Y-144013D01*
X702434Y-141388D01*
X701779Y-139054D01*
X700906Y-137305D01*
X699595Y-135846D01*
X697849Y-135263D01*
G01X715349Y-152763D02*
Y-135263D01*
X712729Y-138763D01*
G01Y-152763D02*
X717969D01*
G01X728046Y-150139D02*
X729355Y-151597D01*
X730884Y-152471D01*
X732849Y-152763D01*
X734814Y-152180D01*
X736342Y-151013D01*
X737434Y-148972D01*
X737652Y-146638D01*
X737216Y-144305D01*
X736124Y-142846D01*
X734595Y-141680D01*
X733067Y-141388D01*
X731539Y-141680D01*
X729574Y-142846D01*
X730229Y-135263D01*
X736124D01*
G01X623046Y-107763D02*
Y-90263D01*
X627412D01*
X629159Y-91138D01*
X630469Y-92305D01*
X631561Y-94054D01*
X632434Y-96097D01*
X632652Y-99013D01*
X632434Y-101930D01*
X631561Y-103972D01*
X630469Y-105722D01*
X629159Y-106888D01*
X627412Y-107763D01*
X623046D01*
G01X649279D02*
Y-96097D01*
G01Y-98138D02*
X648406Y-96972D01*
X647095Y-96388D01*
X645567Y-96097D01*
X644039Y-96680D01*
X642729Y-97846D01*
X641855Y-99596D01*
X641419Y-101930D01*
X641855Y-104263D01*
X642729Y-106013D01*
X644039Y-107180D01*
X645567Y-107763D01*
X647095Y-107471D01*
X648406Y-106597D01*
X649279Y-105430D01*
G01X662849Y-90263D02*
Y-107763D01*
G01X659792Y-96097D02*
X665906D01*
G01X677074Y-99888D02*
X684061D01*
X683406Y-97846D01*
X682314Y-96680D01*
X680786Y-96097D01*
X679257Y-96388D01*
X677947Y-97263D01*
X677074Y-99305D01*
X676637Y-101055D01*
Y-102805D01*
X677074Y-104555D01*
X678166Y-106305D01*
X679476Y-107471D01*
X681004Y-107763D01*
X682532Y-107180D01*
X684061Y-105430D01*
G54D15*
X31299Y230866D03*
Y220866D03*
Y210866D03*
Y348563D03*
Y338563D03*
Y358563D03*
Y903917D03*
Y923917D03*
Y913917D03*
Y1064587D03*
Y1054587D03*
Y1044587D03*
Y1619941D03*
Y1609941D03*
Y1629941D03*
Y1757638D03*
Y1747638D03*
Y1737638D03*
G54D16*
X18035Y572076D03*
X31000Y1280500D03*
X30438Y1367562D03*
X78400Y86100D03*
X58749Y101151D03*
X59104Y441094D03*
X76166Y551466D03*
X38000Y589500D03*
X82900Y620600D03*
X42000Y655500D03*
X79000Y675500D03*
X83900Y659749D03*
X84000Y674000D03*
X56800Y691000D03*
X69600Y662700D03*
X60500Y674700D03*
X80479Y683921D03*
X56800Y831000D03*
X57809Y852500D03*
X67000Y907300D03*
X52000Y867500D03*
X60900Y893000D03*
X54200Y926700D03*
X58500Y912500D03*
X37500Y998000D03*
X57500Y1050500D03*
X58500Y1104500D03*
X56927Y1130027D03*
X76500Y1498500D03*
X81900Y1510200D03*
X37000Y1714000D03*
X75000Y1882000D03*
X71000Y1864500D03*
X127000Y129000D03*
X105300Y525200D03*
X136500Y597000D03*
X131700Y571100D03*
X106400Y648300D03*
X137500Y682500D03*
X132110Y678353D03*
X100600Y656600D03*
X128600Y669500D03*
X104000Y734000D03*
X115217Y765517D03*
X111100Y788200D03*
X116402Y779402D03*
X105763Y814263D03*
X122900Y1007400D03*
X88000Y1034500D03*
X91500Y1093000D03*
X121000Y1133000D03*
Y1147500D03*
X122692Y1257808D03*
X124000Y1247600D03*
X91000Y1272500D03*
X89600Y1464000D03*
X95859Y1448359D03*
X101600Y1431000D03*
X122500Y1437509D03*
X134000Y1519500D03*
X119500Y1501000D03*
X108500Y1501500D03*
X114500Y1501800D03*
X104500Y1506000D03*
X135000Y1500500D03*
X130000Y1501000D03*
X125000Y1500500D03*
X108500Y1556500D03*
X97500Y1901000D03*
X93000Y1884500D03*
X154000Y355500D03*
X179300Y530000D03*
X184003Y536497D03*
X146000Y641400D03*
X166500Y640000D03*
X141800Y676300D03*
X152000Y695688D03*
X173500Y740500D03*
X171000Y1407500D03*
X156000Y1447500D03*
X147500Y1505000D03*
X138500Y1504500D03*
X143518Y1540000D03*
X157000Y1528000D03*
X144500Y1877000D03*
X192007Y482593D03*
G54D17*
X47244Y68110D03*
Y501338D03*
Y761181D03*
Y1207323D03*
Y1467165D03*
Y1900393D03*
G54D18*
X80709Y119409D03*
Y329409D03*
X149606Y119409D03*
Y329409D03*
G54D19*
X80709Y139409D03*
Y309409D03*
X149606Y139409D03*
Y309409D03*
M02*
